#ISCELL
  mstr_misc dns *
  *
#ISCELL
  pure_quanta quanta_title_block_c *
  *
#ISCELL
  pure_quanta_power universal_gnd *
  page176_i1
#CELL
  pure_quanta q_cap *
  page176_i10
#ISCELL
  pure_quanta_power universal_gnd *
  page176_i11
#CELL
  pure_quanta q_cap *
  page176_i12
#CELL
  pure_quanta q_res *
  page176_i13
#ISCELL
  pure_quanta_power universal_gnd *
  page176_i14
#CELL
  pure_quanta q_cap *
  page176_i15
#ISCELL
  pure_quanta_power vcc_core *
  page176_i16
#ISCELL
  pure_quanta_power universal_gnd *
  page176_i17
#CELL
  pure_quanta q_res *
  page176_i18
#ISCELL
  standard offpage *
  page176_i19
#CELL
  pure_quanta q_cap *
  page176_i2
#ISCELL
  standard offpage *
  page176_i20
#CELL
  pure_quanta q_res *
  page176_i21
#ISCELL
  pure_quanta_power vcc_core *
  page176_i22
#ISCELL
  pure_quanta_power universal_gnd *
  page176_i23
#CELL
  pure_quanta q_cap *
  page176_i24
#ISCELL
  standard offpage *
  page176_i25
#ISCELL
  standard offpage *
  page176_i26
#CELL
  pure_quanta q_res *
  page176_i27
#ISCELL
  pure_quanta_power vcc_core *
  page176_i28
#CELL
  pure_quanta q_res *
  page176_i29
#ISCELL
  pure_quanta_power universal_gnd *
  page176_i3
#CELL
  pure_quanta q_cap *
  page176_i30
#ISCELL
  pure_quanta_power universal_gnd *
  page176_i31
#ISCELL
  pure_quanta_power vcc_core *
  page176_i32
#CELL
  pure_quanta isl99390frztr5935 *
  page176_i33
#ISCELL
  pure_quanta_power universal_gnd *
  page176_i34
#CELL
  pure_quanta isl99390frztr5935 *
  page176_i35
#ISCELL
  pure_quanta_power universal_gnd *
  page176_i36
#CELL
  pure_quanta q_cap *
  page176_i37
#ISCELL
  pure_quanta_power universal_gnd *
  page176_i38
#CELL
  pure_quanta q_res *
  page176_i39
#CELL
  pure_quanta q_res *
  page176_i4
#CELL
  pure_quanta q_res *
  page176_i40
#CELL
  pure_quanta q_cap *
  page176_i41
#CELL
  pure_quanta q_res *
  page176_i42
#ISCELL
  standard offpage *
  page176_i43
#CELL
  pure_quanta q_cap *
  page176_i44
#ISCELL
  pure_quanta_power universal_gnd *
  page176_i45
#CELL
  pure_quanta q_inductor4p_14 *
  page176_i46
#CELL
  pure_quanta q_cap *
  page176_i47
#CELL
  pure_quanta q_cap *
  page176_i48
#ISCELL
  pure_quanta_power universal_gnd *
  page176_i49
#ISCELL
  standard offpage *
  page176_i5
#CELL
  pure_quanta q_res *
  page176_i50
#CELL
  pure_quanta q_cap *
  page176_i51
#CELL
  pure_quanta q_cap *
  page176_i52
#ISCELL
  pure_quanta_power vcc_core *
  page176_i53
#CELL
  pure_quanta q_res *
  page176_i54
#CELL
  pure_quanta q_cap *
  page176_i55
#CELL
  pure_quanta q_res *
  page176_i56
#CELL
  pure_quanta q_cap *
  page176_i57
#ISCELL
  standard offpage *
  page176_i58
#CELL
  pure_quanta q_cap *
  page176_i59
#ISCELL
  standard offpage *
  page176_i6
#CELL
  pure_quanta q_cap *
  page176_i60
#CELL
  pure_quanta q_cap *
  page176_i61
#CELL
  pure_quanta q_inductor4p_14 *
  page176_i62
#ISCELL
  pure_quanta_power universal_gnd *
  page176_i63
#CELL
  pure_quanta q_cap *
  page176_i64
#CELL
  pure_quanta q_cap *
  page176_i65
#CELL
  pure_quanta q_capp *
  page176_i66
#ISCELL
  pure_quanta_power vcc_core *
  page176_i67
#ISCELL
  standard offpage *
  page176_i68
#CELL
  pure_quanta q_cap *
  page176_i69
#ISCELL
  standard offpage *
  page176_i7
#CELL
  pure_quanta q_capp *
  page176_i70
#CELL
  pure_quanta q_capp *
  page176_i71
#CELL
  pure_quanta q_capp *
  page176_i72
#CELL
  pure_quanta q_capp *
  page176_i73
#ISCELL
  pure_quanta_power universal_gnd *
  page176_i74
#CELL
  pure_quanta q_capp *
  page176_i75
#ISCELL
  pure_quanta_power vcc_core *
  page176_i76
#CELL
  pure_quanta q_cap *
  page176_i77
#ISCELL
  pure_quanta_power universal_gnd *
  page176_i78
#ISCELL
  pure_quanta_power vcc_core *
  page176_i79
#ISCELL
  standard offpage *
  page176_i8
#ISCELL
  pure_quanta_power universal_gnd *
  page176_i80
#ISCELL
  standard offpage *
  page176_i81
#CELL
  pure_quanta q_capp *
  page176_i82
#CELL
  pure_quanta q_inductor *
  page176_i83
#CELL
  pure_quanta q_cap *
  page176_i84
#ISCELL
  pure_quanta_power universal_gnd *
  page176_i85
#CELL
  pure_quanta q_cap *
  page176_i86
#CELL
  pure_quanta q_cap *
  page176_i87
#ISCELL
  pure_quanta_power vcc_core *
  page176_i88
#CELL
  pure_quanta q_cap *
  page176_i89
#ISCELL
  pure_quanta_power universal_gnd *
  page176_i9
#CELL
  pure_quanta q_res *
  page176_i90
#ISCELL
  pure_quanta_power vcc_core *
  page176_i91
